(kicad_pcb
	(version 20260206)
	(generator "pcbnew")
	(generator_version "10.0")
	(general
		(thickness 1.6)
		(legacy_teardrops no)
	)
	(paper "A4")
	(title_block
		(title "Wiwynn_Tioga_Pass_MB.brd")
		(comment 1 "Tioga Pass / footprints 2661-2668 of 4770")
	)
	(layers
		(0 "F.Cu" signal "TOP")
		(4 "In1.Cu" signal "L2GND")
		(6 "In2.Cu" signal "L3")
		(8 "In3.Cu" signal "L4GND")
		(10 "In4.Cu" signal "L5")
		(12 "In5.Cu" signal "L6GND")
		(14 "In6.Cu" signal "L7VCC")
		(16 "In7.Cu" signal "L8VCC")
		(18 "In8.Cu" signal "L9GND")
		(20 "In9.Cu" signal "L10")
		(22 "In10.Cu" signal "L11GND")
		(24 "In11.Cu" signal "L12")
		(26 "In12.Cu" signal "L13GND")
		(2 "B.Cu" signal "BOTTOM")
		(9 "F.Adhes" user "F.Adhesive")
		(11 "B.Adhes" user "B.Adhesive")
		(13 "F.Paste" user "Package Geometry/Pastemask Top")
		(15 "B.Paste" user "Package Geometry/Pastemask Bottom")
		(5 "F.SilkS" user "Ref Des/Silkscreen Top")
		(7 "B.SilkS" user "Ref Des/Silkscreen Bottom")
		(1 "F.Mask" user "Board Geometry/Soldermask Top")
		(3 "B.Mask" user "Board Geometry/Soldermask Bottom")
		(17 "Dwgs.User" user "User.Drawings")
		(19 "Cmts.User" user "User.Comments")
		(21 "Eco1.User" user "User.Eco1")
		(23 "Eco2.User" user "User.Eco2")
		(25 "Edge.Cuts" user "Board Geometry/Outline")
		(27 "Margin" user)
		(31 "F.CrtYd" user "Package Geometry/Place Bound Top")
		(29 "B.CrtYd" user "Package Geometry/Place Bound Bottom")
		(35 "F.Fab" user "Ref Des/Assembly Top")
		(33 "B.Fab" user "Ref Des/Assembly Bottom")
	)
	(footprint ""
		(layer "B.Cu")
		(at 106.731054 -79.60614 180)
		(property "Reference" "C8P8"
			(at 0 0 0)
			(layer "B.SilkS")
			(hide yes)
			(effects
				(font
					(size 1.27 1.27)
				)
				(justify mirror)
			)
		)
		(property "Value" ""
			(at 0 0 0)
			(layer "B.Fab")
			(effects
				(font
					(size 1.27 1.27)
				)
				(justify mirror)
			)
		)
		(duplicate_pad_numbers_are_jumpers no)
		(fp_poly
			(pts
				(xy 0.7239 -0.2159) (xy -0.7239 -0.2159) (xy -0.7239 1.9939) (xy 0.7239 1.9939)
			)
			(stroke
				(width 0)
				(type default)
			)
			(fill no)
			(layer "B.CrtYd")
		)
		(fp_line
			(start 0.7239 1.9939)
			(end -0.7239 1.9939)
			(stroke
				(width 0.1)
				(type default)
			)
			(layer "B.Fab")
		)
		(fp_line
			(start 0.7239 -0.2159)
			(end 0.7239 1.9939)
			(stroke
				(width 0.1)
				(type default)
			)
			(layer "B.Fab")
		)
		(fp_line
			(start -0.7239 1.9939)
			(end -0.7239 -0.2159)
			(stroke
				(width 0.1)
				(type default)
			)
			(layer "B.Fab")
		)
		(fp_line
			(start -0.7239 -0.2159)
			(end 0.7239 -0.2159)
			(stroke
				(width 0.1)
				(type default)
			)
			(layer "B.Fab")
		)
		(pad "1" smd rect
			(at 0 0)
			(size 1.27 1.016)
			(layers "B.Cu" "B.Mask" "B.Paste")
			(net "PVCCMCP_CPU1")
		)
		(pad "2" smd rect
			(at 0 1.778)
			(size 1.27 1.016)
			(layers "B.Cu" "B.Mask" "B.Paste")
			(net "GND")
		)
		(zone
			(layer "B.Cu")
			(hatch none 0.5)
			(connect_pads
				(clearance 0)
			)
			(min_thickness 0.25)
			(keepout
				(tracks not_allowed)
				(vias allowed)
				(pads allowed)
				(copperpour not_allowed)
				(footprints allowed)
			)
			(placement
				(enabled no)
				(sheetname "")
			)
			(fill
				(thermal_gap 0.5)
				(thermal_bridge_width 0.5)
				(island_removal_mode 0)
			)
			(polygon
				(pts
					(xy 106.096054 -80.11414) (xy 107.366054 -80.11414) (xy 107.366054 -80.87614) (xy 106.096054 -80.87614)
				)
			)
		)
	)
	(footprint ""
		(layer "B.Cu")
		(at 385.826 -140.589 180)
		(property "Reference" "C3L19"
			(at -3.10007 3.24612 270)
			(unlocked yes)
			(layer "B.SilkS")
			(effects
				(font
					(size 0.7874 0.5842)
					(thickness 0.1524)
				)
				(justify mirror)
			)
		)
		(property "Value" ""
			(at 0 0 0)
			(layer "B.Fab")
			(effects
				(font
					(size 1.27 1.27)
				)
				(justify mirror)
			)
		)
		(duplicate_pad_numbers_are_jumpers no)
		(fp_line
			(start 2.563114 1.633728)
			(end 1.6002 1.633728)
			(stroke
				(width 0.1524)
				(type default)
			)
			(layer "B.SilkS")
		)
		(fp_line
			(start 2.563114 -1.616456)
			(end 2.563114 1.633728)
			(stroke
				(width 0.1524)
				(type default)
			)
			(layer "B.SilkS")
		)
		(fp_line
			(start 2.286 7.366)
			(end 2.286 1.632712)
			(stroke
				(width 0.1524)
				(type default)
			)
			(layer "B.SilkS")
		)
		(fp_line
			(start 2.286 7.366)
			(end 1.60147 7.366)
			(stroke
				(width 0.1524)
				(type default)
			)
			(layer "B.SilkS")
		)
		(fp_line
			(start 1.6002 -1.616456)
			(end 2.563114 -1.616456)
			(stroke
				(width 0.1524)
				(type default)
			)
			(layer "B.SilkS")
		)
		(fp_line
			(start -1.6002 -1.616456)
			(end -2.504948 -1.616456)
			(stroke
				(width 0.1524)
				(type default)
			)
			(layer "B.SilkS")
		)
		(fp_line
			(start -2.286 7.366)
			(end -1.600708 7.366)
			(stroke
				(width 0.1524)
				(type default)
			)
			(layer "B.SilkS")
		)
		(fp_line
			(start -2.286 7.366)
			(end -2.286 1.63195)
			(stroke
				(width 0.1524)
				(type default)
			)
			(layer "B.SilkS")
		)
		(fp_line
			(start -2.504948 1.633728)
			(end -1.6002 1.633728)
			(stroke
				(width 0.1524)
				(type default)
			)
			(layer "B.SilkS")
		)
		(fp_line
			(start -2.504948 -1.616456)
			(end -2.504948 1.633728)
			(stroke
				(width 0.1524)
				(type default)
			)
			(layer "B.SilkS")
		)
		(fp_rect
			(start 2.286 7.366)
			(end -2.286 -0.254)
			(stroke
				(width 0)
				(type default)
			)
			(fill no)
			(layer "B.CrtYd")
		)
		(fp_line
			(start 2.286 7.366)
			(end 2.286 -0.254)
			(stroke
				(width 0.1)
				(type default)
			)
			(layer "B.Fab")
		)
		(fp_line
			(start 2.286 -0.254)
			(end -2.286 -0.254)
			(stroke
				(width 0.1)
				(type default)
			)
			(layer "B.Fab")
		)
		(fp_line
			(start -2.286 7.366)
			(end 2.286 7.366)
			(stroke
				(width 0.1)
				(type default)
			)
			(layer "B.Fab")
		)
		(fp_line
			(start -2.286 -0.254)
			(end -2.286 7.366)
			(stroke
				(width 0.1)
				(type default)
			)
			(layer "B.Fab")
		)
		(pad "1" smd rect
			(at 0 0)
			(size 2.54 3.048)
			(layers "B.Cu" "B.Mask" "B.Paste")
			(net "P1V05_PCH_STBY")
		)
		(pad "2" smd rect
			(at 0 7.112)
			(size 2.54 3.048)
			(layers "B.Cu" "B.Mask" "B.Paste")
			(net "GND")
		)
	)
	(footprint ""
		(layer "B.Cu")
		(at 320.194432 -135.382 90)
		(property "Reference" "C4M3"
			(at 0 0 90)
			(layer "B.SilkS")
			(hide yes)
			(effects
				(font
					(size 1.27 1.27)
				)
				(justify mirror)
			)
		)
		(property "Value" ""
			(at 0 0 90)
			(layer "B.Fab")
			(effects
				(font
					(size 1.27 1.27)
				)
				(justify mirror)
			)
		)
		(duplicate_pad_numbers_are_jumpers no)
		(fp_poly
			(pts
				(xy 0.4953 -0.2032) (xy -0.4953 -0.2032) (xy -0.4953 1.6002) (xy 0.4953 1.6002)
			)
			(stroke
				(width 0)
				(type default)
			)
			(fill no)
			(layer "B.CrtYd")
		)
		(fp_line
			(start 0.4953 -0.2032)
			(end -0.4953 -0.2032)
			(stroke
				(width 0.1)
				(type default)
			)
			(layer "B.Fab")
		)
		(fp_line
			(start -0.4953 -0.2032)
			(end -0.4953 1.6002)
			(stroke
				(width 0.1)
				(type default)
			)
			(layer "B.Fab")
		)
		(fp_line
			(start 0.4953 1.6002)
			(end 0.4953 -0.2032)
			(stroke
				(width 0.1)
				(type default)
			)
			(layer "B.Fab")
		)
		(fp_line
			(start -0.4953 1.6002)
			(end 0.4953 1.6002)
			(stroke
				(width 0.1)
				(type default)
			)
			(layer "B.Fab")
		)
		(pad "1" smd rect
			(at 0 0 270)
			(size 0.762 0.889)
			(layers "B.Cu" "B.Mask" "B.Paste")
			(net "PVPP_DEF")
		)
		(pad "2" smd rect
			(at 0 1.397 270)
			(size 0.762 0.889)
			(layers "B.Cu" "B.Mask" "B.Paste")
			(net "GND")
		)
		(zone
			(layer "B.Cu")
			(hatch none 0.5)
			(connect_pads
				(clearance 0)
			)
			(min_thickness 0.25)
			(keepout
				(tracks not_allowed)
				(vias allowed)
				(pads allowed)
				(copperpour not_allowed)
				(footprints allowed)
			)
			(placement
				(enabled no)
				(sheetname "")
			)
			(fill
				(thermal_gap 0.5)
				(thermal_bridge_width 0.5)
				(island_removal_mode 0)
			)
			(polygon
				(pts
					(xy 320.638932 -135.763) (xy 320.638932 -135.001) (xy 321.146932 -135.001) (xy 321.146932 -135.763)
				)
			)
		)
	)
	(footprint ""
		(layer "B.Cu")
		(at 411.21076 -45.53712)
		(property "Reference" "R25W73"
			(at 0.8382 -0.67818 0)
			(unlocked yes)
			(layer "B.SilkS")
			(effects
				(font
					(size 0.4064 0.254)
					(thickness 0.1524)
				)
				(justify left mirror)
			)
		)
		(property "Value" ""
			(at 0 0 0)
			(layer "B.Fab")
			(effects
				(font
					(size 1.27 1.27)
				)
				(justify mirror)
			)
		)
		(duplicate_pad_numbers_are_jumpers no)
		(fp_poly
			(pts
				(xy 0.2794 -0.1016) (xy -0.2794 -0.1016) (xy -0.2794 0.9906) (xy 0.2794 0.9906)
			)
			(stroke
				(width 0)
				(type default)
			)
			(fill no)
			(layer "B.CrtYd")
		)
		(fp_line
			(start -0.2794 -0.1016)
			(end 0.2794 -0.1016)
			(stroke
				(width 0.1)
				(type default)
			)
			(layer "B.Fab")
		)
		(fp_line
			(start -0.2794 0.9906)
			(end -0.2794 -0.1016)
			(stroke
				(width 0.1)
				(type default)
			)
			(layer "B.Fab")
		)
		(fp_line
			(start 0.2794 -0.1016)
			(end 0.2794 0.9906)
			(stroke
				(width 0.1)
				(type default)
			)
			(layer "B.Fab")
		)
		(fp_line
			(start 0.2794 0.9906)
			(end -0.2794 0.9906)
			(stroke
				(width 0.1)
				(type default)
			)
			(layer "B.Fab")
		)
		(pad "1" smd rect
			(at 0 0 180)
			(size 0.508 0.508)
			(layers "B.Cu" "B.Mask" "B.Paste")
			(net "IRQ_LPC_SERIRQ_N")
		)
		(pad "2" smd rect
			(at 0 0.889 180)
			(size 0.508 0.508)
			(layers "B.Cu" "B.Mask" "B.Paste")
			(net "IRQ_LPC_SERIRQ_R")
		)
		(zone
			(layer "B.Cu")
			(hatch none 0.5)
			(connect_pads
				(clearance 0)
			)
			(min_thickness 0.25)
			(keepout
				(tracks allowed)
				(vias not_allowed)
				(pads allowed)
				(copperpour not_allowed)
				(footprints allowed)
			)
			(placement
				(enabled no)
				(sheetname "")
			)
			(fill
				(thermal_gap 0.5)
				(thermal_bridge_width 0.5)
				(island_removal_mode 0)
			)
			(polygon
				(pts
					(xy 411.46476 -45.28312) (xy 410.95676 -45.28312) (xy 410.95676 -44.90212) (xy 411.46476 -44.90212)
				)
			)
		)
		(zone
			(layer "B.Cu")
			(hatch none 0.5)
			(connect_pads
				(clearance 0)
			)
			(min_thickness 0.25)
			(keepout
				(tracks not_allowed)
				(vias allowed)
				(pads allowed)
				(copperpour not_allowed)
				(footprints allowed)
			)
			(placement
				(enabled no)
				(sheetname "")
			)
			(fill
				(thermal_gap 0.5)
				(thermal_bridge_width 0.5)
				(island_removal_mode 0)
			)
			(polygon
				(pts
					(xy 411.46476 -44.90212) (xy 410.95676 -44.90212) (xy 410.95676 -45.28312) (xy 411.46476 -45.28312)
				)
			)
		)
	)
	(footprint ""
		(layer "B.Cu")
		(at 491.4392 -115.3668 180)
		(property "Reference" "R9W1"
			(at 0.8382 -0.67818 180)
			(unlocked yes)
			(layer "B.SilkS")
			(effects
				(font
					(size 0.4064 0.254)
					(thickness 0.1524)
				)
				(justify left mirror)
			)
		)
		(property "Value" ""
			(at 0 0 0)
			(layer "B.Fab")
			(effects
				(font
					(size 1.27 1.27)
				)
				(justify mirror)
			)
		)
		(duplicate_pad_numbers_are_jumpers no)
		(fp_poly
			(pts
				(xy 0.2794 -0.1016) (xy -0.2794 -0.1016) (xy -0.2794 0.9906) (xy 0.2794 0.9906)
			)
			(stroke
				(width 0)
				(type default)
			)
			(fill no)
			(layer "B.CrtYd")
		)
		(fp_line
			(start 0.2794 0.9906)
			(end -0.2794 0.9906)
			(stroke
				(width 0.1)
				(type default)
			)
			(layer "B.Fab")
		)
		(fp_line
			(start 0.2794 -0.1016)
			(end 0.2794 0.9906)
			(stroke
				(width 0.1)
				(type default)
			)
			(layer "B.Fab")
		)
		(fp_line
			(start -0.2794 0.9906)
			(end -0.2794 -0.1016)
			(stroke
				(width 0.1)
				(type default)
			)
			(layer "B.Fab")
		)
		(fp_line
			(start -0.2794 -0.1016)
			(end 0.2794 -0.1016)
			(stroke
				(width 0.1)
				(type default)
			)
			(layer "B.Fab")
		)
		(pad "1" smd rect
			(at 0 0)
			(size 0.508 0.508)
			(layers "B.Cu" "B.Mask" "B.Paste")
			(net "P3V3_STBY")
		)
		(pad "2" smd rect
			(at 0 0.889)
			(size 0.508 0.508)
			(layers "B.Cu" "B.Mask" "B.Paste")
			(net "FM_MEZZA_PRSNT1_N")
		)
		(zone
			(layer "B.Cu")
			(hatch none 0.5)
			(connect_pads
				(clearance 0)
			)
			(min_thickness 0.25)
			(keepout
				(tracks not_allowed)
				(vias allowed)
				(pads allowed)
				(copperpour not_allowed)
				(footprints allowed)
			)
			(placement
				(enabled no)
				(sheetname "")
			)
			(fill
				(thermal_gap 0.5)
				(thermal_bridge_width 0.5)
				(island_removal_mode 0)
			)
			(polygon
				(pts
					(xy 491.1852 -116.0018) (xy 491.6932 -116.0018) (xy 491.6932 -115.6208) (xy 491.1852 -115.6208)
				)
			)
		)
		(zone
			(layer "B.Cu")
			(hatch none 0.5)
			(connect_pads
				(clearance 0)
			)
			(min_thickness 0.25)
			(keepout
				(tracks allowed)
				(vias not_allowed)
				(pads allowed)
				(copperpour not_allowed)
				(footprints allowed)
			)
			(placement
				(enabled no)
				(sheetname "")
			)
			(fill
				(thermal_gap 0.5)
				(thermal_bridge_width 0.5)
				(island_removal_mode 0)
			)
			(polygon
				(pts
					(xy 491.1852 -115.6208) (xy 491.6932 -115.6208) (xy 491.6932 -116.0018) (xy 491.1852 -116.0018)
				)
			)
		)
	)
	(footprint ""
		(layer "B.Cu")
		(at 276.7076 -28.2956 90)
		(property "Reference" "C5T4"
			(at 0 0 90)
			(layer "B.SilkS")
			(hide yes)
			(effects
				(font
					(size 1.27 1.27)
				)
				(justify mirror)
			)
		)
		(property "Value" ""
			(at 0 0 90)
			(layer "B.Fab")
			(effects
				(font
					(size 1.27 1.27)
				)
				(justify mirror)
			)
		)
		(duplicate_pad_numbers_are_jumpers no)
		(fp_rect
			(start 0.500126 1.598422)
			(end -0.500126 -0.201422)
			(stroke
				(width 0)
				(type default)
			)
			(fill no)
			(layer "B.CrtYd")
		)
		(fp_line
			(start 0.500126 -0.201422)
			(end -0.500126 -0.201422)
			(stroke
				(width 0.1)
				(type default)
			)
			(layer "B.Fab")
		)
		(fp_line
			(start -0.500126 -0.201422)
			(end -0.500126 1.598422)
			(stroke
				(width 0.1)
				(type default)
			)
			(layer "B.Fab")
		)
		(fp_line
			(start 0.500126 1.598422)
			(end 0.500126 -0.201422)
			(stroke
				(width 0.1)
				(type default)
			)
			(layer "B.Fab")
		)
		(fp_line
			(start -0.500126 1.598422)
			(end 0.500126 1.598422)
			(stroke
				(width 0.1)
				(type default)
			)
			(layer "B.Fab")
		)
		(pad "1" smd rect
			(at 0 0)
			(size 0.889 0.9906)
			(layers "B.Cu" "B.Mask" "B.Paste")
			(net "PVDDQ_ABC")
		)
		(pad "2" smd rect
			(at 0 1.397)
			(size 0.889 0.9906)
			(layers "B.Cu" "B.Mask" "B.Paste")
			(net "GND")
		)
		(zone
			(layer "B.Cu")
			(hatch none 0.5)
			(connect_pads
				(clearance 0)
			)
			(min_thickness 0.25)
			(keepout
				(tracks allowed)
				(vias not_allowed)
				(pads allowed)
				(copperpour not_allowed)
				(footprints allowed)
			)
			(placement
				(enabled no)
				(sheetname "")
			)
			(fill
				(thermal_gap 0.5)
				(thermal_bridge_width 0.5)
				(island_removal_mode 0)
			)
			(polygon
				(pts
					(xy 277.6601 -28.7909) (xy 277.1521 -28.7909) (xy 277.1521 -27.8003) (xy 277.6601 -27.8003)
				)
			)
		)
		(zone
			(layer "B.Cu")
			(hatch none 0.5)
			(connect_pads
				(clearance 0)
			)
			(min_thickness 0.25)
			(keepout
				(tracks not_allowed)
				(vias allowed)
				(pads allowed)
				(copperpour not_allowed)
				(footprints allowed)
			)
			(placement
				(enabled no)
				(sheetname "")
			)
			(fill
				(thermal_gap 0.5)
				(thermal_bridge_width 0.5)
				(island_removal_mode 0)
			)
			(polygon
				(pts
					(xy 277.6601 -28.7909) (xy 277.1521 -28.7909) (xy 277.1521 -27.8003) (xy 277.6601 -27.8003)
				)
			)
		)
	)
	(footprint ""
		(layer "B.Cu")
		(at 466.344 -116.49202)
		(property "Reference" "C1M6"
			(at 0 0 0)
			(layer "B.SilkS")
			(hide yes)
			(effects
				(font
					(size 1.27 1.27)
				)
				(justify mirror)
			)
		)
		(property "Value" ""
			(at 0 0 0)
			(layer "B.Fab")
			(effects
				(font
					(size 1.27 1.27)
				)
				(justify mirror)
			)
		)
		(duplicate_pad_numbers_are_jumpers no)
		(fp_rect
			(start -0.3048 0.9906)
			(end 0.3048 -0.1016)
			(stroke
				(width 0)
				(type default)
			)
			(fill no)
			(layer "B.CrtYd")
		)
		(fp_line
			(start -0.3048 -0.1016)
			(end 0.3048 -0.1016)
			(stroke
				(width 0.1)
				(type default)
			)
			(layer "B.Fab")
		)
		(fp_line
			(start -0.3048 0.9906)
			(end -0.3048 -0.1016)
			(stroke
				(width 0.1)
				(type default)
			)
			(layer "B.Fab")
		)
		(fp_line
			(start 0.3048 -0.1016)
			(end 0.3048 0.9906)
			(stroke
				(width 0.1)
				(type default)
			)
			(layer "B.Fab")
		)
		(fp_line
			(start 0.3048 0.9906)
			(end -0.3048 0.9906)
			(stroke
				(width 0.1)
				(type default)
			)
			(layer "B.Fab")
		)
		(pad "1" smd rect
			(at 0 0 180)
			(size 0.508 0.508)
			(layers "B.Cu" "B.Mask" "B.Paste")
			(net "P3E_CPU0_PE3_OCP_TXP<15>")
		)
		(pad "2" smd rect
			(at 0 0.889 180)
			(size 0.508 0.508)
			(layers "B.Cu" "B.Mask" "B.Paste")
			(net "P3E_OCP_CPU0_PE3_C_TXP<15>")
		)
		(zone
			(layer "B.Cu")
			(hatch none 0.5)
			(connect_pads
				(clearance 0)
			)
			(min_thickness 0.25)
			(keepout
				(tracks allowed)
				(vias not_allowed)
				(pads allowed)
				(copperpour not_allowed)
				(footprints allowed)
			)
			(placement
				(enabled no)
				(sheetname "")
			)
			(fill
				(thermal_gap 0.5)
				(thermal_bridge_width 0.5)
				(island_removal_mode 0)
			)
			(polygon
				(pts
					(xy 466.09 -115.85702) (xy 466.598 -115.85702) (xy 466.598 -116.23802) (xy 466.09 -116.23802)
				)
			)
		)
		(zone
			(layer "B.Cu")
			(hatch none 0.5)
			(connect_pads
				(clearance 0)
			)
			(min_thickness 0.25)
			(keepout
				(tracks not_allowed)
				(vias allowed)
				(pads allowed)
				(copperpour not_allowed)
				(footprints allowed)
			)
			(placement
				(enabled no)
				(sheetname "")
			)
			(fill
				(thermal_gap 0.5)
				(thermal_bridge_width 0.5)
				(island_removal_mode 0)
			)
			(polygon
				(pts
					(xy 466.09 -115.85702) (xy 466.598 -115.85702) (xy 466.598 -116.23802) (xy 466.09 -116.23802)
				)
			)
		)
	)
	(footprint ""
		(layer "B.Cu")
		(at 102.551992 -85.075014)
		(property "Reference" "C8P1"
			(at 0 0 0)
			(layer "B.SilkS")
			(hide yes)
			(effects
				(font
					(size 1.27 1.27)
				)
				(justify mirror)
			)
		)
		(property "Value" ""
			(at 0 0 0)
			(layer "B.Fab")
			(effects
				(font
					(size 1.27 1.27)
				)
				(justify mirror)
			)
		)
		(duplicate_pad_numbers_are_jumpers no)
		(fp_poly
			(pts
				(xy 0.7239 -0.2159) (xy -0.7239 -0.2159) (xy -0.7239 1.9939) (xy 0.7239 1.9939)
			)
			(stroke
				(width 0)
				(type default)
			)
			(fill no)
			(layer "B.CrtYd")
		)
		(fp_line
			(start -0.7239 -0.2159)
			(end 0.7239 -0.2159)
			(stroke
				(width 0.1)
				(type default)
			)
			(layer "B.Fab")
		)
		(fp_line
			(start -0.7239 1.9939)
			(end -0.7239 -0.2159)
			(stroke
				(width 0.1)
				(type default)
			)
			(layer "B.Fab")
		)
		(fp_line
			(start 0.7239 -0.2159)
			(end 0.7239 1.9939)
			(stroke
				(width 0.1)
				(type default)
			)
			(layer "B.Fab")
		)
		(fp_line
			(start 0.7239 1.9939)
			(end -0.7239 1.9939)
			(stroke
				(width 0.1)
				(type default)
			)
			(layer "B.Fab")
		)
		(pad "1" smd rect
			(at 0 0 180)
			(size 1.27 1.016)
			(layers "B.Cu" "B.Mask" "B.Paste")
			(net "PVDDQ_KLM")
		)
		(pad "2" smd rect
			(at 0 1.778 180)
			(size 1.27 1.016)
			(layers "B.Cu" "B.Mask" "B.Paste")
			(net "GND")
		)
		(zone
			(layer "B.Cu")
			(hatch none 0.5)
			(connect_pads
				(clearance 0)
			)
			(min_thickness 0.25)
			(keepout
				(tracks not_allowed)
				(vias allowed)
				(pads allowed)
				(copperpour not_allowed)
				(footprints allowed)
			)
			(placement
				(enabled no)
				(sheetname "")
			)
			(fill
				(thermal_gap 0.5)
				(thermal_bridge_width 0.5)
				(island_removal_mode 0)
			)
			(polygon
				(pts
					(xy 103.186992 -84.567014) (xy 101.916992 -84.567014) (xy 101.916992 -83.805014) (xy 103.186992 -83.805014)
				)
			)
		)
	)
)
